(kicad_pcb
	(version 20260206)
	(generator "pcbnew")
	(generator_version "10.0")
	(general
		(thickness 1.6)
		(legacy_teardrops no)
	)
	(paper "A4")
	(title_block
		(title "01162023_DA0F0TEBIF0_F0T_Expander_BD_F_brd_V02_OCP.brd")
		(comment 1 "Grand Teton / footprints 7516-7524 of 9728")
	)
	(layers
		(0 "F.Cu" signal "TOP")
		(4 "In1.Cu" signal "GND")
		(6 "In2.Cu" signal "VCC")
		(8 "In3.Cu" signal "VCC1")
		(10 "In4.Cu" signal "GND1")
		(12 "In5.Cu" signal "IN1")
		(14 "In6.Cu" signal "GND2")
		(16 "In7.Cu" signal "IN2")
		(18 "In8.Cu" signal "GND3")
		(20 "In9.Cu" signal "IN3")
		(22 "In10.Cu" signal "GND4")
		(24 "In11.Cu" signal "IN4")
		(26 "In12.Cu" signal "GND5")
		(28 "In13.Cu" signal "IN5")
		(30 "In14.Cu" signal "GND6")
		(32 "In15.Cu" signal "IN6")
		(34 "In16.Cu" signal "GND7")
		(2 "B.Cu" signal "BOTTOM")
		(9 "F.Adhes" user "F.Adhesive")
		(11 "B.Adhes" user "B.Adhesive")
		(13 "F.Paste" user "Package Geometry/Pastemask Top")
		(15 "B.Paste" user "Package Geometry/Pastemask Bottom")
		(5 "F.SilkS" user "Ref Des/Silkscreen Top")
		(7 "B.SilkS" user "Ref Des/Silkscreen Bottom")
		(1 "F.Mask" user "Board Geometry/Soldermask Top")
		(3 "B.Mask" user "Board Geometry/Soldermask Bottom")
		(17 "Dwgs.User" user "User.Drawings")
		(19 "Cmts.User" user "User.Comments")
		(21 "Eco1.User" user "User.Eco1")
		(23 "Eco2.User" user "User.Eco2")
		(25 "Edge.Cuts" user "Board Geometry/Outline")
		(27 "Margin" user)
		(31 "F.CrtYd" user "Package Geometry/Place Bound Top")
		(29 "B.CrtYd" user "Package Geometry/Place Bound Bottom")
		(35 "F.Fab" user "Ref Des/Assembly Top")
		(33 "B.Fab" user "Ref Des/Assembly Bottom")
	)
	(footprint ""
		(layer "B.Cu")
		(at 394.65504 -301.0408)
		(property "Reference" "C3521"
			(at 0 0 0)
			(layer "B.SilkS")
			(hide yes)
			(effects
				(font
					(size 1.27 1.27)
				)
				(justify mirror)
			)
		)
		(property "Value" ""
			(at 0 0 0)
			(layer "B.Fab")
			(effects
				(font
					(size 1.27 1.27)
				)
				(justify mirror)
			)
		)
		(duplicate_pad_numbers_are_jumpers no)
		(fp_line
			(start -0.299974 -0.150114)
			(end -0.299974 0.150114)
			(stroke
				(width 0.1)
				(type default)
			)
			(layer "B.Fab")
		)
		(fp_line
			(start -0.299974 0.150114)
			(end 0.299974 0.150114)
			(stroke
				(width 0.1)
				(type default)
			)
			(layer "B.Fab")
		)
		(fp_line
			(start 0.299974 -0.150114)
			(end -0.299974 -0.150114)
			(stroke
				(width 0.1)
				(type default)
			)
			(layer "B.Fab")
		)
		(fp_line
			(start 0.299974 0.150114)
			(end 0.299974 -0.150114)
			(stroke
				(width 0.1)
				(type default)
			)
			(layer "B.Fab")
		)
		(pad "1" smd rect
			(at 0.2667 0 180)
			(size 0.3048 0.381)
			(layers "B.Cu" "B.Mask" "B.Paste")
			(net "P1V8_PEX")
		)
		(pad "2" smd rect
			(at -0.2667 0 180)
			(size 0.3048 0.381)
			(layers "B.Cu" "B.Mask" "B.Paste")
			(net "GND")
		)
	)
	(footprint ""
		(layer "B.Cu")
		(at 198.539608 -367.333276)
		(property "Reference" "PR4"
			(at 0 0 0)
			(layer "B.SilkS")
			(hide yes)
			(effects
				(font
					(size 1.27 1.27)
				)
				(justify mirror)
			)
		)
		(property "Value" ""
			(at 0 0 0)
			(layer "B.Fab")
			(effects
				(font
					(size 1.27 1.27)
				)
				(justify mirror)
			)
		)
		(duplicate_pad_numbers_are_jumpers no)
		(fp_line
			(start -0.7874 -0.4064)
			(end -0.7874 0.4064)
			(stroke
				(width 0.1524)
				(type default)
			)
			(layer "B.SilkS")
		)
		(fp_line
			(start -0.7874 0.4064)
			(end 0.7874 0.4064)
			(stroke
				(width 0.1524)
				(type default)
			)
			(layer "B.SilkS")
		)
		(fp_line
			(start 0.7874 -0.4064)
			(end -0.7874 -0.4064)
			(stroke
				(width 0.1524)
				(type default)
			)
			(layer "B.SilkS")
		)
		(fp_line
			(start 0.7874 0.4064)
			(end 0.7874 -0.4064)
			(stroke
				(width 0.1524)
				(type default)
			)
			(layer "B.SilkS")
		)
		(fp_line
			(start -0.67945 -0.3048)
			(end -0.67945 0.3048)
			(stroke
				(width 0.1)
				(type default)
			)
			(layer "B.Fab")
		)
		(fp_line
			(start -0.67945 0.3048)
			(end -0.120396 0.3048)
			(stroke
				(width 0.1)
				(type default)
			)
			(layer "B.Fab")
		)
		(fp_line
			(start -0.12065 -0.3048)
			(end -0.67945 -0.3048)
			(stroke
				(width 0.1)
				(type default)
			)
			(layer "B.Fab")
		)
		(fp_line
			(start -0.12065 -0.2794)
			(end -0.12065 -0.3048)
			(stroke
				(width 0.1)
				(type default)
			)
			(layer "B.Fab")
		)
		(fp_line
			(start -0.120396 0.2794)
			(end 0.12065 0.2794)
			(stroke
				(width 0.1)
				(type default)
			)
			(layer "B.Fab")
		)
		(fp_line
			(start -0.120396 0.3048)
			(end -0.120396 0.2794)
			(stroke
				(width 0.1)
				(type default)
			)
			(layer "B.Fab")
		)
		(fp_line
			(start 0.12065 -0.305054)
			(end 0.12065 -0.2794)
			(stroke
				(width 0.1)
				(type default)
			)
			(layer "B.Fab")
		)
		(fp_line
			(start 0.12065 -0.2794)
			(end -0.12065 -0.2794)
			(stroke
				(width 0.1)
				(type default)
			)
			(layer "B.Fab")
		)
		(fp_line
			(start 0.12065 0.2794)
			(end 0.12065 0.3048)
			(stroke
				(width 0.1)
				(type default)
			)
			(layer "B.Fab")
		)
		(fp_line
			(start 0.12065 0.3048)
			(end 0.67945 0.3048)
			(stroke
				(width 0.1)
				(type default)
			)
			(layer "B.Fab")
		)
		(fp_line
			(start 0.67945 -0.305054)
			(end 0.12065 -0.305054)
			(stroke
				(width 0.1)
				(type default)
			)
			(layer "B.Fab")
		)
		(fp_line
			(start 0.67945 0.3048)
			(end 0.67945 -0.305054)
			(stroke
				(width 0.1)
				(type default)
			)
			(layer "B.Fab")
		)
		(pad "1" smd circle
			(at 0.40005 0 180)
			(size 0 0)
			(layers "B.Cu" "B.Mask" "B.Paste")
			(net "HSC_VDD_R")
		)
		(pad "2" smd circle
			(at -0.40005 0 180)
			(size 0 0)
			(layers "B.Cu" "B.Mask" "B.Paste")
			(net "HSC_VDD")
		)
	)
	(footprint ""
		(layer "B.Cu")
		(at 185.104024 -117.723666)
		(property "Reference" "C887"
			(at 0 0 0)
			(layer "B.SilkS")
			(hide yes)
			(effects
				(font
					(size 1.27 1.27)
				)
				(justify mirror)
			)
		)
		(property "Value" ""
			(at 0 0 0)
			(layer "B.Fab")
			(effects
				(font
					(size 1.27 1.27)
				)
				(justify mirror)
			)
		)
		(duplicate_pad_numbers_are_jumpers no)
		(fp_line
			(start -0.7874 -0.4064)
			(end -0.7874 0.4064)
			(stroke
				(width 0.1524)
				(type default)
			)
			(layer "B.SilkS")
		)
		(fp_line
			(start -0.7874 0.4064)
			(end 0.7874 0.4064)
			(stroke
				(width 0.1524)
				(type default)
			)
			(layer "B.SilkS")
		)
		(fp_line
			(start 0.7874 -0.4064)
			(end -0.7874 -0.4064)
			(stroke
				(width 0.1524)
				(type default)
			)
			(layer "B.SilkS")
		)
		(fp_line
			(start 0.7874 0.4064)
			(end 0.7874 -0.4064)
			(stroke
				(width 0.1524)
				(type default)
			)
			(layer "B.SilkS")
		)
		(fp_line
			(start -0.67945 -0.3048)
			(end -0.67945 0.3048)
			(stroke
				(width 0.1)
				(type default)
			)
			(layer "B.Fab")
		)
		(fp_line
			(start -0.67945 0.3048)
			(end -0.120396 0.3048)
			(stroke
				(width 0.1)
				(type default)
			)
			(layer "B.Fab")
		)
		(fp_line
			(start -0.12065 -0.3048)
			(end -0.67945 -0.3048)
			(stroke
				(width 0.1)
				(type default)
			)
			(layer "B.Fab")
		)
		(fp_line
			(start -0.12065 -0.2794)
			(end -0.12065 -0.3048)
			(stroke
				(width 0.1)
				(type default)
			)
			(layer "B.Fab")
		)
		(fp_line
			(start -0.120396 0.2794)
			(end 0.12065 0.2794)
			(stroke
				(width 0.1)
				(type default)
			)
			(layer "B.Fab")
		)
		(fp_line
			(start -0.120396 0.3048)
			(end -0.120396 0.2794)
			(stroke
				(width 0.1)
				(type default)
			)
			(layer "B.Fab")
		)
		(fp_line
			(start 0.12065 -0.305054)
			(end 0.12065 -0.2794)
			(stroke
				(width 0.1)
				(type default)
			)
			(layer "B.Fab")
		)
		(fp_line
			(start 0.12065 -0.2794)
			(end -0.12065 -0.2794)
			(stroke
				(width 0.1)
				(type default)
			)
			(layer "B.Fab")
		)
		(fp_line
			(start 0.12065 0.2794)
			(end 0.12065 0.3048)
			(stroke
				(width 0.1)
				(type default)
			)
			(layer "B.Fab")
		)
		(fp_line
			(start 0.12065 0.3048)
			(end 0.67945 0.3048)
			(stroke
				(width 0.1)
				(type default)
			)
			(layer "B.Fab")
		)
		(fp_line
			(start 0.67945 -0.305054)
			(end 0.12065 -0.305054)
			(stroke
				(width 0.1)
				(type default)
			)
			(layer "B.Fab")
		)
		(fp_line
			(start 0.67945 0.3048)
			(end 0.67945 -0.305054)
			(stroke
				(width 0.1)
				(type default)
			)
			(layer "B.Fab")
		)
		(pad "1" smd circle
			(at 0.40005 0 180)
			(size 0 0)
			(layers "B.Cu" "B.Mask" "B.Paste")
			(net "P3V3_AUX")
		)
		(pad "2" smd circle
			(at -0.40005 0 180)
			(size 0 0)
			(layers "B.Cu" "B.Mask" "B.Paste")
			(net "GND")
		)
	)
	(footprint ""
		(layer "B.Cu")
		(at 350.888554 -277.639272)
		(property "Reference" "PC6621"
			(at 0 0 0)
			(layer "B.SilkS")
			(hide yes)
			(effects
				(font
					(size 1.27 1.27)
				)
				(justify mirror)
			)
		)
		(property "Value" ""
			(at 0 0 0)
			(layer "B.Fab")
			(effects
				(font
					(size 1.27 1.27)
				)
				(justify mirror)
			)
		)
		(duplicate_pad_numbers_are_jumpers no)
		(fp_line
			(start -1.524 -0.762)
			(end -1.524 0.762)
			(stroke
				(width 0.1524)
				(type default)
			)
			(layer "B.SilkS")
		)
		(fp_line
			(start -1.524 0.762)
			(end 1.524 0.762)
			(stroke
				(width 0.1524)
				(type default)
			)
			(layer "B.SilkS")
		)
		(fp_line
			(start 1.524 -0.762)
			(end -1.524 -0.762)
			(stroke
				(width 0.1524)
				(type default)
			)
			(layer "B.SilkS")
		)
		(fp_line
			(start 1.524 0.762)
			(end 1.524 -0.762)
			(stroke
				(width 0.1524)
				(type default)
			)
			(layer "B.SilkS")
		)
		(fp_line
			(start -1.1049 -0.724916)
			(end 1.1049 -0.724916)
			(stroke
				(width 0.1)
				(type default)
			)
			(layer "B.Fab")
		)
		(fp_line
			(start -1.1049 0.724916)
			(end -1.1049 -0.724916)
			(stroke
				(width 0.1)
				(type default)
			)
			(layer "B.Fab")
		)
		(fp_line
			(start 1.1049 -0.724916)
			(end 1.1049 0.724916)
			(stroke
				(width 0.1)
				(type default)
			)
			(layer "B.Fab")
		)
		(fp_line
			(start 1.1049 0.724916)
			(end -1.1049 0.724916)
			(stroke
				(width 0.1)
				(type default)
			)
			(layer "B.Fab")
		)
		(pad "1" smd rect
			(at 0.889 0)
			(size 1.016 1.27)
			(layers "B.Cu" "B.Mask" "B.Paste")
			(net "SW_P12V_P0V8_PEX3_FLT")
		)
		(pad "2" smd rect
			(at -0.889 0)
			(size 1.016 1.27)
			(layers "B.Cu" "B.Mask" "B.Paste")
			(net "GND")
		)
	)
	(footprint ""
		(layer "B.Cu")
		(at 52.049934 -292.099746 90)
		(property "Reference" "C1187"
			(at 0 0 90)
			(layer "B.SilkS")
			(hide yes)
			(effects
				(font
					(size 1.27 1.27)
				)
				(justify mirror)
			)
		)
		(property "Value" ""
			(at 0 0 90)
			(layer "B.Fab")
			(effects
				(font
					(size 1.27 1.27)
				)
				(justify mirror)
			)
		)
		(duplicate_pad_numbers_are_jumpers no)
		(fp_line
			(start 0.299974 -0.150114)
			(end -0.299974 -0.150114)
			(stroke
				(width 0.1)
				(type default)
			)
			(layer "B.Fab")
		)
		(fp_line
			(start -0.299974 -0.150114)
			(end -0.299974 0.150114)
			(stroke
				(width 0.1)
				(type default)
			)
			(layer "B.Fab")
		)
		(fp_line
			(start 0.299974 0.150114)
			(end 0.299974 -0.150114)
			(stroke
				(width 0.1)
				(type default)
			)
			(layer "B.Fab")
		)
		(fp_line
			(start -0.299974 0.150114)
			(end 0.299974 0.150114)
			(stroke
				(width 0.1)
				(type default)
			)
			(layer "B.Fab")
		)
		(pad "1" smd rect
			(at 0.2667 0 270)
			(size 0.3048 0.381)
			(layers "B.Cu" "B.Mask" "B.Paste")
			(net "P0V8_SERDES_VDDA_PEX0")
		)
		(pad "2" smd rect
			(at -0.2667 0 270)
			(size 0.3048 0.381)
			(layers "B.Cu" "B.Mask" "B.Paste")
			(net "GND")
		)
	)
	(footprint ""
		(layer "B.Cu")
		(at 279.3492 -384.403092)
		(property "Reference" "PR7159"
			(at 0 0 0)
			(layer "B.SilkS")
			(hide yes)
			(effects
				(font
					(size 1.27 1.27)
				)
				(justify mirror)
			)
		)
		(property "Value" ""
			(at 0 0 0)
			(layer "B.Fab")
			(effects
				(font
					(size 1.27 1.27)
				)
				(justify mirror)
			)
		)
		(duplicate_pad_numbers_are_jumpers no)
		(fp_line
			(start -0.7874 -0.4064)
			(end -0.7874 0.4064)
			(stroke
				(width 0.1524)
				(type default)
			)
			(layer "B.SilkS")
		)
		(fp_line
			(start -0.7874 0.4064)
			(end 0.7874 0.4064)
			(stroke
				(width 0.1524)
				(type default)
			)
			(layer "B.SilkS")
		)
		(fp_line
			(start 0.7874 -0.4064)
			(end -0.7874 -0.4064)
			(stroke
				(width 0.1524)
				(type default)
			)
			(layer "B.SilkS")
		)
		(fp_line
			(start 0.7874 0.4064)
			(end 0.7874 -0.4064)
			(stroke
				(width 0.1524)
				(type default)
			)
			(layer "B.SilkS")
		)
		(fp_line
			(start -0.67945 -0.3048)
			(end -0.67945 0.3048)
			(stroke
				(width 0.1)
				(type default)
			)
			(layer "B.Fab")
		)
		(fp_line
			(start -0.67945 0.3048)
			(end -0.120396 0.3048)
			(stroke
				(width 0.1)
				(type default)
			)
			(layer "B.Fab")
		)
		(fp_line
			(start -0.12065 -0.3048)
			(end -0.67945 -0.3048)
			(stroke
				(width 0.1)
				(type default)
			)
			(layer "B.Fab")
		)
		(fp_line
			(start -0.12065 -0.2794)
			(end -0.12065 -0.3048)
			(stroke
				(width 0.1)
				(type default)
			)
			(layer "B.Fab")
		)
		(fp_line
			(start -0.120396 0.2794)
			(end 0.12065 0.2794)
			(stroke
				(width 0.1)
				(type default)
			)
			(layer "B.Fab")
		)
		(fp_line
			(start -0.120396 0.3048)
			(end -0.120396 0.2794)
			(stroke
				(width 0.1)
				(type default)
			)
			(layer "B.Fab")
		)
		(fp_line
			(start 0.12065 -0.305054)
			(end 0.12065 -0.2794)
			(stroke
				(width 0.1)
				(type default)
			)
			(layer "B.Fab")
		)
		(fp_line
			(start 0.12065 -0.2794)
			(end -0.12065 -0.2794)
			(stroke
				(width 0.1)
				(type default)
			)
			(layer "B.Fab")
		)
		(fp_line
			(start 0.12065 0.2794)
			(end 0.12065 0.3048)
			(stroke
				(width 0.1)
				(type default)
			)
			(layer "B.Fab")
		)
		(fp_line
			(start 0.12065 0.3048)
			(end 0.67945 0.3048)
			(stroke
				(width 0.1)
				(type default)
			)
			(layer "B.Fab")
		)
		(fp_line
			(start 0.67945 -0.305054)
			(end 0.12065 -0.305054)
			(stroke
				(width 0.1)
				(type default)
			)
			(layer "B.Fab")
		)
		(fp_line
			(start 0.67945 0.3048)
			(end 0.67945 -0.305054)
			(stroke
				(width 0.1)
				(type default)
			)
			(layer "B.Fab")
		)
		(pad "1" smd circle
			(at 0.40005 0 180)
			(size 0 0)
			(layers "B.Cu" "B.Mask" "B.Paste")
			(net "LTC4282_T_CRIT_N")
		)
		(pad "2" smd circle
			(at -0.40005 0 180)
			(size 0 0)
			(layers "B.Cu" "B.Mask" "B.Paste")
			(net "P3V3_AUX")
		)
	)
	(footprint ""
		(layer "B.Cu")
		(at 298.974764 -286.399732 90)
		(property "Reference" "C3313"
			(at 0 0 90)
			(layer "B.SilkS")
			(hide yes)
			(effects
				(font
					(size 1.27 1.27)
				)
				(justify mirror)
			)
		)
		(property "Value" ""
			(at 0 0 90)
			(layer "B.Fab")
			(effects
				(font
					(size 1.27 1.27)
				)
				(justify mirror)
			)
		)
		(duplicate_pad_numbers_are_jumpers no)
		(fp_line
			(start 0.299974 -0.150114)
			(end -0.299974 -0.150114)
			(stroke
				(width 0.1)
				(type default)
			)
			(layer "B.Fab")
		)
		(fp_line
			(start -0.299974 -0.150114)
			(end -0.299974 0.150114)
			(stroke
				(width 0.1)
				(type default)
			)
			(layer "B.Fab")
		)
		(fp_line
			(start 0.299974 0.150114)
			(end 0.299974 -0.150114)
			(stroke
				(width 0.1)
				(type default)
			)
			(layer "B.Fab")
		)
		(fp_line
			(start -0.299974 0.150114)
			(end 0.299974 0.150114)
			(stroke
				(width 0.1)
				(type default)
			)
			(layer "B.Fab")
		)
		(pad "1" smd rect
			(at 0.2667 0 270)
			(size 0.3048 0.381)
			(layers "B.Cu" "B.Mask" "B.Paste")
			(net "P1V25_SERDES_VDDPLL_PEX2")
		)
		(pad "2" smd rect
			(at -0.2667 0 270)
			(size 0.3048 0.381)
			(layers "B.Cu" "B.Mask" "B.Paste")
			(net "GND")
		)
	)
	(footprint ""
		(layer "B.Cu")
		(at 353.523296 -223.750632)
		(property "Reference" "R5635"
			(at 0 0 0)
			(layer "B.SilkS")
			(hide yes)
			(effects
				(font
					(size 1.27 1.27)
				)
				(justify mirror)
			)
		)
		(property "Value" ""
			(at 0 0 0)
			(layer "B.Fab")
			(effects
				(font
					(size 1.27 1.27)
				)
				(justify mirror)
			)
		)
		(duplicate_pad_numbers_are_jumpers no)
		(fp_line
			(start -1.2954 -0.5842)
			(end -1.2954 0.5842)
			(stroke
				(width 0.1524)
				(type default)
			)
			(layer "B.SilkS")
		)
		(fp_line
			(start -1.2954 0.5842)
			(end 1.2954 0.5842)
			(stroke
				(width 0.1524)
				(type default)
			)
			(layer "B.SilkS")
		)
		(fp_line
			(start 1.2954 -0.5842)
			(end -1.2954 -0.5842)
			(stroke
				(width 0.1524)
				(type default)
			)
			(layer "B.SilkS")
		)
		(fp_line
			(start 1.2954 0.5842)
			(end 1.2954 -0.5842)
			(stroke
				(width 0.1524)
				(type default)
			)
			(layer "B.SilkS")
		)
		(fp_line
			(start -1.1938 -0.406654)
			(end -1.1938 0.4064)
			(stroke
				(width 0.1)
				(type default)
			)
			(layer "B.Fab")
		)
		(fp_line
			(start -1.1938 0.4064)
			(end -0.8636 0.4064)
			(stroke
				(width 0.1)
				(type default)
			)
			(layer "B.Fab")
		)
		(fp_line
			(start -0.8636 -0.4572)
			(end -0.8636 -0.406654)
			(stroke
				(width 0.1)
				(type default)
			)
			(layer "B.Fab")
		)
		(fp_line
			(start -0.8636 -0.406654)
			(end -1.1938 -0.406654)
			(stroke
				(width 0.1)
				(type default)
			)
			(layer "B.Fab")
		)
		(fp_line
			(start -0.8636 0.4064)
			(end -0.8636 0.4572)
			(stroke
				(width 0.1)
				(type default)
			)
			(layer "B.Fab")
		)
		(fp_line
			(start -0.8636 0.4572)
			(end 0.8636 0.4572)
			(stroke
				(width 0.1)
				(type default)
			)
			(layer "B.Fab")
		)
		(fp_line
			(start 0.8636 -0.4572)
			(end -0.8636 -0.4572)
			(stroke
				(width 0.1)
				(type default)
			)
			(layer "B.Fab")
		)
		(fp_line
			(start 0.8636 -0.406654)
			(end 0.8636 -0.4572)
			(stroke
				(width 0.1)
				(type default)
			)
			(layer "B.Fab")
		)
		(fp_line
			(start 0.8636 0.4064)
			(end 1.1938 0.4064)
			(stroke
				(width 0.1)
				(type default)
			)
			(layer "B.Fab")
		)
		(fp_line
			(start 0.8636 0.4318)
			(end 0.8636 0.4064)
			(stroke
				(width 0.1)
				(type default)
			)
			(layer "B.Fab")
		)
		(fp_line
			(start 0.8636 0.4572)
			(end 0.8636 0.4318)
			(stroke
				(width 0.1)
				(type default)
			)
			(layer "B.Fab")
		)
		(fp_line
			(start 1.1938 -0.406654)
			(end 0.8636 -0.406654)
			(stroke
				(width 0.1)
				(type default)
			)
			(layer "B.Fab")
		)
		(fp_line
			(start 1.1938 0.4064)
			(end 1.1938 -0.406654)
			(stroke
				(width 0.1)
				(type default)
			)
			(layer "B.Fab")
		)
		(pad "1" smd rect
			(at 0.7366 0 270)
			(size 0.7112 0.8128)
			(layers "B.Cu" "B.Mask" "B.Paste")
			(net "P3V3_AUX")
		)
		(pad "2" smd rect
			(at -0.7366 0 270)
			(size 0.7112 0.8128)
			(layers "B.Cu" "B.Mask" "B.Paste")
			(net "P3V3_VCC_FPGA_CORE")
		)
	)
	(footprint ""
		(layer "B.Cu")
		(at 56.325008 -297.79976 -90)
		(property "Reference" "C1154"
			(at 0 0 90)
			(layer "B.SilkS")
			(hide yes)
			(effects
				(font
					(size 1.27 1.27)
				)
				(justify mirror)
			)
		)
		(property "Value" ""
			(at 0 0 90)
			(layer "B.Fab")
			(effects
				(font
					(size 1.27 1.27)
				)
				(justify mirror)
			)
		)
		(duplicate_pad_numbers_are_jumpers no)
		(fp_line
			(start -0.299974 0.150114)
			(end 0.299974 0.150114)
			(stroke
				(width 0.1)
				(type default)
			)
			(layer "B.Fab")
		)
		(fp_line
			(start 0.299974 0.150114)
			(end 0.299974 -0.150114)
			(stroke
				(width 0.1)
				(type default)
			)
			(layer "B.Fab")
		)
		(fp_line
			(start -0.299974 -0.150114)
			(end -0.299974 0.150114)
			(stroke
				(width 0.1)
				(type default)
			)
			(layer "B.Fab")
		)
		(fp_line
			(start 0.299974 -0.150114)
			(end -0.299974 -0.150114)
			(stroke
				(width 0.1)
				(type default)
			)
			(layer "B.Fab")
		)
		(pad "1" smd rect
			(at 0.2667 0 90)
			(size 0.3048 0.381)
			(layers "B.Cu" "B.Mask" "B.Paste")
			(net "P0V8_PEX0")
		)
		(pad "2" smd rect
			(at -0.2667 0 90)
			(size 0.3048 0.381)
			(layers "B.Cu" "B.Mask" "B.Paste")
			(net "GND")
		)
	)
)
